(kicad_pcb
	(version 20260206)
	(generator "pcbnew")
	(generator_version "10.0")
	(general
		(thickness 1.6)
		(legacy_teardrops no)
	)
	(paper "A4")
	(title_block
		(title "4HDD Backplane_Layout.brd")
		(comment 1 "Tioga Pass / footprints 25-25 of 97")
	)
	(layers
		(0 "F.Cu" signal "TOP")
		(4 "In1.Cu" signal "L2GND")
		(6 "In2.Cu" signal "L3")
		(8 "In3.Cu" signal "L4")
		(10 "In4.Cu" signal "L5GND")
		(2 "B.Cu" signal "BOTTOM")
		(9 "F.Adhes" user "F.Adhesive")
		(11 "B.Adhes" user "B.Adhesive")
		(13 "F.Paste" user "Package Geometry/Pastemask Top")
		(15 "B.Paste" user "Package Geometry/Pastemask Bottom")
		(5 "F.SilkS" user "Ref Des/Silkscreen Top")
		(7 "B.SilkS" user "Ref Des/Silkscreen Bottom")
		(1 "F.Mask" user "Board Geometry/Soldermask Top")
		(3 "B.Mask" user "Board Geometry/Soldermask Bottom")
		(17 "Dwgs.User" user "User.Drawings")
		(19 "Cmts.User" user "User.Comments")
		(21 "Eco1.User" user "User.Eco1")
		(23 "Eco2.User" user "User.Eco2")
		(25 "Edge.Cuts" user "Board Geometry/Outline")
		(27 "Margin" user)
		(31 "F.CrtYd" user "Package Geometry/Place Bound Top")
		(29 "B.CrtYd" user "Package Geometry/Place Bound Bottom")
		(35 "F.Fab" user "Ref Des/Assembly Top")
		(33 "B.Fab" user "Ref Des/Assembly Bottom")
	)
	(footprint ""
		(layer "F.Cu")
		(at 52.705 -19.431 180)
		(property "Reference" "C13"
			(at 0 0 180)
			(layer "F.SilkS")
			(hide yes)
			(effects
				(font
					(size 1.27 1.27)
				)
			)
		)
		(property "Value" "SCD01U50V2KX-1GP"
			(at 1.1811 -2.7051 180)
			(unlocked yes)
			(layer "F.Fab")
			(hide yes)
			(effects
				(font
					(size 1.016 1.016)
					(thickness 0.1524)
				)
			)
		)
		(property "Device Type" "C402H22"
			(at 1.1811 -4.2291 180)
			(unlocked yes)
			(layer "F.Fab")
			(hide yes)
			(effects
				(font
					(size 1.016 1.016)
					(thickness 0.1524)
				)
			)
		)
		(duplicate_pad_numbers_are_jumpers no)
		(fp_rect
			(start -0.4318 0.9525)
			(end 0.4318 -0.9525)
			(stroke
				(width 0)
				(type default)
			)
			(fill no)
			(layer "F.CrtYd")
		)
		(fp_rect
			(start -0.4318 0.9525)
			(end 0.4318 -0.9525)
			(stroke
				(width 0)
				(type default)
			)
			(fill no)
			(layer "F.Fab")
		)
		(pad "1" smd custom
			(at 0 -0.4445 180)
			(size 0.1524 0.1524)
			(layers "F.Cu" "F.Mask" "F.Paste")
			(net "HBA_PRSNT2_N")
			(options
				(clearance outline)
				(anchor circle)
			)
			(primitives
				(gr_poly
					(pts
						(arc
							(start 0.3048 -0.2032)
							(mid 0.275042 -0.275042)
							(end 0.2032 -0.3048)
						)
						(arc
							(start -0.2032 -0.3048)
							(mid -0.275042 -0.275042)
							(end -0.3048 -0.2032)
						)
						(arc
							(start -0.3048 0.2032)
							(mid -0.275042 0.275042)
							(end -0.2032 0.3048)
						)
						(arc
							(start 0.2032 0.3048)
							(mid 0.275042 0.275042)
							(end 0.3048 0.2032)
						)
					)
					(width 0)
					(fill yes)
				)
			)
		)
		(pad "2" smd custom
			(at 0 0.4445 180)
			(size 0.1524 0.1524)
			(layers "F.Cu" "F.Mask" "F.Paste")
			(net "GND")
			(options
				(clearance outline)
				(anchor circle)
			)
			(primitives
				(gr_poly
					(pts
						(arc
							(start 0.3048 -0.2032)
							(mid 0.275042 -0.275042)
							(end 0.2032 -0.3048)
						)
						(arc
							(start -0.2032 -0.3048)
							(mid -0.275042 -0.275042)
							(end -0.3048 -0.2032)
						)
						(arc
							(start -0.3048 0.2032)
							(mid -0.275042 0.275042)
							(end -0.2032 0.3048)
						)
						(arc
							(start 0.2032 0.3048)
							(mid 0.275042 0.275042)
							(end 0.3048 0.2032)
						)
					)
					(width 0)
					(fill yes)
				)
			)
		)
	)
)
